(kicad_pcb
	(version 20260206)
	(generator "pcbnew")
	(generator_version "10.0")
	(general
		(thickness 1.6)
		(legacy_teardrops no)
	)
	(paper "A4")
	(title_block
		(title "03242023_DA0F0TMBIJ0_F0T_Motherboard_J_brd_V01_OCP.brd")
		(comment 1 "Grand Teton / footprints 562-567 of 6105")
	)
	(layers
		(0 "F.Cu" signal "TOP")
		(4 "In1.Cu" signal "GND")
		(6 "In2.Cu" signal "IN1")
		(8 "In3.Cu" signal "GND1")
		(10 "In4.Cu" signal "IN2")
		(12 "In5.Cu" signal "GND2")
		(14 "In6.Cu" signal "IN3")
		(16 "In7.Cu" signal "GND3")
		(18 "In8.Cu" signal "VCC")
		(20 "In9.Cu" signal "VCC1")
		(22 "In10.Cu" signal "GND4")
		(24 "In11.Cu" signal "IN4")
		(26 "In12.Cu" signal "GND5")
		(28 "In13.Cu" signal "IN5")
		(30 "In14.Cu" signal "GND6")
		(32 "In15.Cu" signal "IN6")
		(34 "In16.Cu" signal "GND7")
		(2 "B.Cu" signal "BOTTOM")
		(9 "F.Adhes" user "F.Adhesive")
		(11 "B.Adhes" user "B.Adhesive")
		(13 "F.Paste" user "Package Geometry/Pastemask Top")
		(15 "B.Paste" user "Package Geometry/Pastemask Bottom")
		(5 "F.SilkS" user "Ref Des/Silkscreen Top")
		(7 "B.SilkS" user "Ref Des/Silkscreen Bottom")
		(1 "F.Mask" user "Board Geometry/Soldermask Top")
		(3 "B.Mask" user "Board Geometry/Soldermask Bottom")
		(17 "Dwgs.User" user "User.Drawings")
		(19 "Cmts.User" user "User.Comments")
		(21 "Eco1.User" user "User.Eco1")
		(23 "Eco2.User" user "User.Eco2")
		(25 "Edge.Cuts" user "Board Geometry/Outline")
		(27 "Margin" user)
		(31 "F.CrtYd" user "Package Geometry/Place Bound Top")
		(29 "B.CrtYd" user "Package Geometry/Place Bound Bottom")
		(35 "F.Fab" user "Ref Des/Assembly Top")
		(33 "B.Fab" user "Ref Des/Assembly Bottom")
	)
	(footprint ""
		(layer "F.Cu")
		(at 123.370848 -361.563158 90)
		(property "Reference" "PC1265"
			(at 0 0 90)
			(layer "F.SilkS")
			(hide yes)
			(effects
				(font
					(size 1.27 1.27)
				)
			)
		)
		(property "Value" ""
			(at 0 0 90)
			(layer "F.Fab")
			(effects
				(font
					(size 1.27 1.27)
				)
			)
		)
		(duplicate_pad_numbers_are_jumpers no)
		(fp_line
			(start 0.7874 -0.4064)
			(end 0.7874 0.4064)
			(stroke
				(width 0.1524)
				(type default)
			)
			(layer "F.SilkS")
		)
		(fp_line
			(start -0.7874 -0.4064)
			(end 0.7874 -0.4064)
			(stroke
				(width 0.1524)
				(type default)
			)
			(layer "F.SilkS")
		)
		(fp_line
			(start 0.7874 0.4064)
			(end -0.7874 0.4064)
			(stroke
				(width 0.1524)
				(type default)
			)
			(layer "F.SilkS")
		)
		(fp_line
			(start -0.7874 0.4064)
			(end -0.7874 -0.4064)
			(stroke
				(width 0.1524)
				(type default)
			)
			(layer "F.SilkS")
		)
		(fp_line
			(start -0.12065 -0.305054)
			(end -0.12065 -0.2794)
			(stroke
				(width 0.1)
				(type default)
			)
			(layer "F.Fab")
		)
		(fp_line
			(start -0.67945 -0.305054)
			(end -0.12065 -0.305054)
			(stroke
				(width 0.1)
				(type default)
			)
			(layer "F.Fab")
		)
		(fp_line
			(start 0.67945 -0.3048)
			(end 0.67945 0.3048)
			(stroke
				(width 0.1)
				(type default)
			)
			(layer "F.Fab")
		)
		(fp_line
			(start 0.12065 -0.3048)
			(end 0.67945 -0.3048)
			(stroke
				(width 0.1)
				(type default)
			)
			(layer "F.Fab")
		)
		(fp_line
			(start 0.12065 -0.2794)
			(end 0.12065 -0.3048)
			(stroke
				(width 0.1)
				(type default)
			)
			(layer "F.Fab")
		)
		(fp_line
			(start -0.12065 -0.2794)
			(end 0.12065 -0.2794)
			(stroke
				(width 0.1)
				(type default)
			)
			(layer "F.Fab")
		)
		(fp_line
			(start 0.120396 0.2794)
			(end -0.12065 0.2794)
			(stroke
				(width 0.1)
				(type default)
			)
			(layer "F.Fab")
		)
		(fp_line
			(start -0.12065 0.2794)
			(end -0.12065 0.3048)
			(stroke
				(width 0.1)
				(type default)
			)
			(layer "F.Fab")
		)
		(fp_line
			(start 0.67945 0.3048)
			(end 0.120396 0.3048)
			(stroke
				(width 0.1)
				(type default)
			)
			(layer "F.Fab")
		)
		(fp_line
			(start 0.120396 0.3048)
			(end 0.120396 0.2794)
			(stroke
				(width 0.1)
				(type default)
			)
			(layer "F.Fab")
		)
		(fp_line
			(start -0.12065 0.3048)
			(end -0.67945 0.3048)
			(stroke
				(width 0.1)
				(type default)
			)
			(layer "F.Fab")
		)
		(fp_line
			(start -0.67945 0.3048)
			(end -0.67945 -0.305054)
			(stroke
				(width 0.1)
				(type default)
			)
			(layer "F.Fab")
		)
		(pad "1" smd circle
			(at -0.40005 0 90)
			(size 0 0)
			(layers "F.Cu" "F.Mask" "F.Paste")
			(net "SW_PVPP_HBM_CPU1_BST")
		)
		(pad "2" smd circle
			(at 0.40005 0 90)
			(size 0 0)
			(layers "F.Cu" "F.Mask" "F.Paste")
			(net "SW_PVPP_HBM_CPU1_SW")
		)
	)
	(footprint ""
		(layer "F.Cu")
		(at 76.90231 -74.901552 -90)
		(property "Reference" "R3094"
			(at 0 0 270)
			(layer "F.SilkS")
			(hide yes)
			(effects
				(font
					(size 1.27 1.27)
				)
			)
		)
		(property "Value" ""
			(at 0 0 270)
			(layer "F.Fab")
			(effects
				(font
					(size 1.27 1.27)
				)
			)
		)
		(duplicate_pad_numbers_are_jumpers no)
		(fp_line
			(start -0.7874 0.4064)
			(end -0.7874 -0.4064)
			(stroke
				(width 0.1524)
				(type default)
			)
			(layer "F.SilkS")
		)
		(fp_line
			(start 0.7874 0.4064)
			(end -0.7874 0.4064)
			(stroke
				(width 0.1524)
				(type default)
			)
			(layer "F.SilkS")
		)
		(fp_line
			(start -0.7874 -0.4064)
			(end 0.7874 -0.4064)
			(stroke
				(width 0.1524)
				(type default)
			)
			(layer "F.SilkS")
		)
		(fp_line
			(start 0.7874 -0.4064)
			(end 0.7874 0.4064)
			(stroke
				(width 0.1524)
				(type default)
			)
			(layer "F.SilkS")
		)
		(fp_line
			(start -0.67945 0.3048)
			(end -0.67945 -0.305054)
			(stroke
				(width 0.1)
				(type default)
			)
			(layer "F.Fab")
		)
		(fp_line
			(start -0.12065 0.3048)
			(end -0.67945 0.3048)
			(stroke
				(width 0.1)
				(type default)
			)
			(layer "F.Fab")
		)
		(fp_line
			(start 0.120396 0.3048)
			(end 0.120396 0.2794)
			(stroke
				(width 0.1)
				(type default)
			)
			(layer "F.Fab")
		)
		(fp_line
			(start 0.67945 0.3048)
			(end 0.120396 0.3048)
			(stroke
				(width 0.1)
				(type default)
			)
			(layer "F.Fab")
		)
		(fp_line
			(start -0.12065 0.2794)
			(end -0.12065 0.3048)
			(stroke
				(width 0.1)
				(type default)
			)
			(layer "F.Fab")
		)
		(fp_line
			(start 0.120396 0.2794)
			(end -0.12065 0.2794)
			(stroke
				(width 0.1)
				(type default)
			)
			(layer "F.Fab")
		)
		(fp_line
			(start -0.12065 -0.2794)
			(end 0.12065 -0.2794)
			(stroke
				(width 0.1)
				(type default)
			)
			(layer "F.Fab")
		)
		(fp_line
			(start 0.12065 -0.2794)
			(end 0.12065 -0.3048)
			(stroke
				(width 0.1)
				(type default)
			)
			(layer "F.Fab")
		)
		(fp_line
			(start 0.12065 -0.3048)
			(end 0.67945 -0.3048)
			(stroke
				(width 0.1)
				(type default)
			)
			(layer "F.Fab")
		)
		(fp_line
			(start 0.67945 -0.3048)
			(end 0.67945 0.3048)
			(stroke
				(width 0.1)
				(type default)
			)
			(layer "F.Fab")
		)
		(fp_line
			(start -0.67945 -0.305054)
			(end -0.12065 -0.305054)
			(stroke
				(width 0.1)
				(type default)
			)
			(layer "F.Fab")
		)
		(fp_line
			(start -0.12065 -0.305054)
			(end -0.12065 -0.2794)
			(stroke
				(width 0.1)
				(type default)
			)
			(layer "F.Fab")
		)
		(pad "1" smd circle
			(at -0.40005 0 270)
			(size 0 0)
			(layers "F.Cu" "F.Mask" "F.Paste")
			(net "LED_PWRGD_PVPP_HBM_CPU1")
		)
		(pad "2" smd circle
			(at 0.40005 0 270)
			(size 0 0)
			(layers "F.Cu" "F.Mask" "F.Paste")
			(net "P3V3_AUX")
		)
	)
	(footprint ""
		(layer "F.Cu")
		(at 428.179992 -386.171948)
		(property "Reference" "Q71"
			(at 0.546608 -2.16789 0)
			(unlocked yes)
			(layer "F.SilkS")
			(effects
				(font
					(size 0.7874 0.5842)
					(thickness 0.1524)
				)
				(justify left)
			)
		)
		(property "Value" ""
			(at 0 0 0)
			(layer "F.Fab")
			(effects
				(font
					(size 1.27 1.27)
				)
			)
		)
		(duplicate_pad_numbers_are_jumpers no)
		(fp_line
			(start -1.332738 -1.100074)
			(end -0.4826 -1.100074)
			(stroke
				(width 0.1524)
				(type default)
			)
			(layer "F.SilkS")
		)
		(fp_line
			(start -1.332738 1.100074)
			(end -1.332738 -1.100074)
			(stroke
				(width 0.1524)
				(type default)
			)
			(layer "F.SilkS")
		)
		(fp_line
			(start -0.4826 -1.100074)
			(end 0 -0.541274)
			(stroke
				(width 0.1524)
				(type default)
			)
			(layer "F.SilkS")
		)
		(fp_line
			(start 0 -0.541274)
			(end 0.4826 -1.100074)
			(stroke
				(width 0.1524)
				(type default)
			)
			(layer "F.SilkS")
		)
		(fp_line
			(start 0.4826 -1.100074)
			(end 1.332738 -1.100074)
			(stroke
				(width 0.1524)
				(type default)
			)
			(layer "F.SilkS")
		)
		(fp_line
			(start 1.332738 -1.100074)
			(end 1.332738 1.100074)
			(stroke
				(width 0.1524)
				(type default)
			)
			(layer "F.SilkS")
		)
		(fp_line
			(start 1.332738 1.100074)
			(end -1.332738 1.100074)
			(stroke
				(width 0.1524)
				(type default)
			)
			(layer "F.SilkS")
		)
		(fp_poly
			(pts
				(xy -0.639318 -2.126488) (xy -0.990346 -1.424432) (xy -1.341374 -2.126488)
			)
			(stroke
				(width 0)
				(type default)
			)
			(fill yes)
			(layer "F.SilkS")
		)
		(fp_line
			(start -0.674878 -1.100074)
			(end 0.674878 -1.100074)
			(stroke
				(width 0.1)
				(type default)
			)
			(layer "F.Fab")
		)
		(fp_line
			(start -0.674878 1.100074)
			(end -0.674878 -1.100074)
			(stroke
				(width 0.1)
				(type default)
			)
			(layer "F.Fab")
		)
		(fp_line
			(start 0.674878 -1.100074)
			(end 0.674878 1.100074)
			(stroke
				(width 0.1)
				(type default)
			)
			(layer "F.Fab")
		)
		(fp_line
			(start 0.674878 1.100074)
			(end -0.674878 1.100074)
			(stroke
				(width 0.1)
				(type default)
			)
			(layer "F.Fab")
		)
		(fp_poly
			(pts
				(xy -2.2352 -0.298958) (xy -2.2352 -1.001014) (xy -1.533144 -0.649986)
			)
			(stroke
				(width 0)
				(type default)
			)
			(fill yes)
			(layer "F.Fab")
		)
		(pad "1" smd rect
			(at -0.94996 -0.649986 90)
			(size 0.4318 0.508)
			(layers "F.Cu" "F.Mask" "F.Paste")
			(net "GND")
		)
		(pad "2" smd rect
			(at -0.94996 0 90)
			(size 0.4318 0.508)
			(layers "F.Cu" "F.Mask" "F.Paste")
			(net "FM_SWB_PWRGD")
		)
		(pad "3" smd rect
			(at -0.94996 0.649986 90)
			(size 0.4318 0.508)
			(layers "F.Cu" "F.Mask" "F.Paste")
			(net "FM_SWB_PWRGD_ISO")
		)
		(pad "4" smd rect
			(at 0.94996 0.649986 90)
			(size 0.4318 0.508)
			(layers "F.Cu" "F.Mask" "F.Paste")
			(net "GND")
		)
		(pad "5" smd rect
			(at 0.94996 0 90)
			(size 0.4318 0.508)
			(layers "F.Cu" "F.Mask" "F.Paste")
			(net "FM_SWB_PWRGD_N")
		)
		(pad "6" smd rect
			(at 0.94996 -0.649986 90)
			(size 0.4318 0.508)
			(layers "F.Cu" "F.Mask" "F.Paste")
			(net "FM_SWB_PWRGD_N")
		)
	)
	(footprint ""
		(layer "F.Cu")
		(at 42.708576 -58.655712)
		(property "Reference" "D143"
			(at 4.258564 -0.413258 0)
			(unlocked yes)
			(layer "F.SilkS")
			(effects
				(font
					(size 0.7874 0.5842)
					(thickness 0.1524)
				)
				(justify left)
			)
		)
		(property "Value" ""
			(at 0 0 0)
			(layer "F.Fab")
			(effects
				(font
					(size 1.27 1.27)
				)
			)
		)
		(duplicate_pad_numbers_are_jumpers no)
		(fp_line
			(start -0.90678 0.4826)
			(end -0.90678 -0.4699)
			(stroke
				(width 0.1524)
				(type default)
			)
			(layer "F.SilkS")
		)
		(fp_line
			(start -0.89408 -0.4826)
			(end 0.90678 -0.4826)
			(stroke
				(width 0.1524)
				(type default)
			)
			(layer "F.SilkS")
		)
		(fp_line
			(start -0.79248 -0.4826)
			(end 1.03378 -0.4826)
			(stroke
				(width 0.1524)
				(type default)
			)
			(layer "F.SilkS")
		)
		(fp_line
			(start -0.64008 -0.4826)
			(end 1.16078 -0.4826)
			(stroke
				(width 0.1524)
				(type default)
			)
			(layer "F.SilkS")
		)
		(fp_line
			(start 0.90678 -0.4826)
			(end 0.90678 0.4826)
			(stroke
				(width 0.1524)
				(type default)
			)
			(layer "F.SilkS")
		)
		(fp_line
			(start 0.90678 0.4826)
			(end -0.90678 0.4826)
			(stroke
				(width 0.1524)
				(type default)
			)
			(layer "F.SilkS")
		)
		(fp_line
			(start 1.03378 -0.4826)
			(end 1.03378 0.4826)
			(stroke
				(width 0.1524)
				(type default)
			)
			(layer "F.SilkS")
		)
		(fp_line
			(start 1.03378 0.4826)
			(end -0.79248 0.4826)
			(stroke
				(width 0.1524)
				(type default)
			)
			(layer "F.SilkS")
		)
		(fp_line
			(start 1.16078 -0.4826)
			(end 1.16078 0.4826)
			(stroke
				(width 0.1524)
				(type default)
			)
			(layer "F.SilkS")
		)
		(fp_line
			(start 1.16078 0.4826)
			(end -0.64008 0.4826)
			(stroke
				(width 0.1524)
				(type default)
			)
			(layer "F.SilkS")
		)
		(fp_line
			(start -0.499872 -0.249936)
			(end 0.499872 -0.249936)
			(stroke
				(width 0.1)
				(type default)
			)
			(layer "F.Fab")
		)
		(fp_line
			(start -0.499872 0.249936)
			(end -0.499872 -0.249936)
			(stroke
				(width 0.1)
				(type default)
			)
			(layer "F.Fab")
		)
		(fp_line
			(start 0.499872 -0.249936)
			(end 0.499872 0.249936)
			(stroke
				(width 0.1)
				(type default)
			)
			(layer "F.Fab")
		)
		(fp_line
			(start 0.499872 0.249936)
			(end -0.499872 0.249936)
			(stroke
				(width 0.1)
				(type default)
			)
			(layer "F.Fab")
		)
		(pad "A" smd rect
			(at -0.47498 0)
			(size 0.6096 0.7112)
			(layers "F.Cu" "F.Mask" "F.Paste")
			(net "LED_P12V_PSU_R1")
		)
		(pad "C" smd rect
			(at 0.47498 0)
			(size 0.6096 0.7112)
			(layers "F.Cu" "F.Mask" "F.Paste")
			(net "GND")
		)
	)
	(footprint ""
		(layer "F.Cu")
		(at 143.90116 -112.434624)
		(property "Reference" "R4759"
			(at 0 0 0)
			(layer "F.SilkS")
			(hide yes)
			(effects
				(font
					(size 1.27 1.27)
				)
			)
		)
		(property "Value" ""
			(at 0 0 0)
			(layer "F.Fab")
			(effects
				(font
					(size 1.27 1.27)
				)
			)
		)
		(duplicate_pad_numbers_are_jumpers no)
		(fp_line
			(start -0.7874 -0.4064)
			(end 0.7874 -0.4064)
			(stroke
				(width 0.1524)
				(type default)
			)
			(layer "F.SilkS")
		)
		(fp_line
			(start -0.7874 0.4064)
			(end -0.7874 -0.4064)
			(stroke
				(width 0.1524)
				(type default)
			)
			(layer "F.SilkS")
		)
		(fp_line
			(start 0.7874 -0.4064)
			(end 0.7874 0.4064)
			(stroke
				(width 0.1524)
				(type default)
			)
			(layer "F.SilkS")
		)
		(fp_line
			(start 0.7874 0.4064)
			(end -0.7874 0.4064)
			(stroke
				(width 0.1524)
				(type default)
			)
			(layer "F.SilkS")
		)
		(fp_line
			(start -0.67945 -0.305054)
			(end -0.12065 -0.305054)
			(stroke
				(width 0.1)
				(type default)
			)
			(layer "F.Fab")
		)
		(fp_line
			(start -0.67945 0.3048)
			(end -0.67945 -0.305054)
			(stroke
				(width 0.1)
				(type default)
			)
			(layer "F.Fab")
		)
		(fp_line
			(start -0.12065 -0.305054)
			(end -0.12065 -0.2794)
			(stroke
				(width 0.1)
				(type default)
			)
			(layer "F.Fab")
		)
		(fp_line
			(start -0.12065 -0.2794)
			(end 0.12065 -0.2794)
			(stroke
				(width 0.1)
				(type default)
			)
			(layer "F.Fab")
		)
		(fp_line
			(start -0.12065 0.2794)
			(end -0.12065 0.3048)
			(stroke
				(width 0.1)
				(type default)
			)
			(layer "F.Fab")
		)
		(fp_line
			(start -0.12065 0.3048)
			(end -0.67945 0.3048)
			(stroke
				(width 0.1)
				(type default)
			)
			(layer "F.Fab")
		)
		(fp_line
			(start 0.120396 0.2794)
			(end -0.12065 0.2794)
			(stroke
				(width 0.1)
				(type default)
			)
			(layer "F.Fab")
		)
		(fp_line
			(start 0.120396 0.3048)
			(end 0.120396 0.2794)
			(stroke
				(width 0.1)
				(type default)
			)
			(layer "F.Fab")
		)
		(fp_line
			(start 0.12065 -0.3048)
			(end 0.67945 -0.3048)
			(stroke
				(width 0.1)
				(type default)
			)
			(layer "F.Fab")
		)
		(fp_line
			(start 0.12065 -0.2794)
			(end 0.12065 -0.3048)
			(stroke
				(width 0.1)
				(type default)
			)
			(layer "F.Fab")
		)
		(fp_line
			(start 0.67945 -0.3048)
			(end 0.67945 0.3048)
			(stroke
				(width 0.1)
				(type default)
			)
			(layer "F.Fab")
		)
		(fp_line
			(start 0.67945 0.3048)
			(end 0.120396 0.3048)
			(stroke
				(width 0.1)
				(type default)
			)
			(layer "F.Fab")
		)
		(pad "1" smd circle
			(at -0.40005 0)
			(size 0 0)
			(layers "F.Cu" "F.Mask" "F.Paste")
			(net "OCP_V3_2_AUX_PWR_EN_R2")
		)
		(pad "2" smd circle
			(at 0.40005 0)
			(size 0 0)
			(layers "F.Cu" "F.Mask" "F.Paste")
			(net "OCP_V3_2_AUX_PWR_EN")
		)
	)
	(footprint ""
		(layer "F.Cu")
		(at 420.14394 -109.271308 -90)
		(property "Reference" "R3845"
			(at 0 0 270)
			(layer "F.SilkS")
			(hide yes)
			(effects
				(font
					(size 1.27 1.27)
				)
			)
		)
		(property "Value" ""
			(at 0 0 270)
			(layer "F.Fab")
			(effects
				(font
					(size 1.27 1.27)
				)
			)
		)
		(duplicate_pad_numbers_are_jumpers no)
		(fp_line
			(start -0.7874 0.4064)
			(end -0.7874 -0.4064)
			(stroke
				(width 0.1524)
				(type default)
			)
			(layer "F.SilkS")
		)
		(fp_line
			(start 0.7874 0.4064)
			(end -0.7874 0.4064)
			(stroke
				(width 0.1524)
				(type default)
			)
			(layer "F.SilkS")
		)
		(fp_line
			(start -0.7874 -0.4064)
			(end 0.7874 -0.4064)
			(stroke
				(width 0.1524)
				(type default)
			)
			(layer "F.SilkS")
		)
		(fp_line
			(start 0.7874 -0.4064)
			(end 0.7874 0.4064)
			(stroke
				(width 0.1524)
				(type default)
			)
			(layer "F.SilkS")
		)
		(fp_line
			(start -0.67945 0.3048)
			(end -0.67945 -0.305054)
			(stroke
				(width 0.1)
				(type default)
			)
			(layer "F.Fab")
		)
		(fp_line
			(start -0.12065 0.3048)
			(end -0.67945 0.3048)
			(stroke
				(width 0.1)
				(type default)
			)
			(layer "F.Fab")
		)
		(fp_line
			(start 0.120396 0.3048)
			(end 0.120396 0.2794)
			(stroke
				(width 0.1)
				(type default)
			)
			(layer "F.Fab")
		)
		(fp_line
			(start 0.67945 0.3048)
			(end 0.120396 0.3048)
			(stroke
				(width 0.1)
				(type default)
			)
			(layer "F.Fab")
		)
		(fp_line
			(start -0.12065 0.2794)
			(end -0.12065 0.3048)
			(stroke
				(width 0.1)
				(type default)
			)
			(layer "F.Fab")
		)
		(fp_line
			(start 0.120396 0.2794)
			(end -0.12065 0.2794)
			(stroke
				(width 0.1)
				(type default)
			)
			(layer "F.Fab")
		)
		(fp_line
			(start -0.12065 -0.2794)
			(end 0.12065 -0.2794)
			(stroke
				(width 0.1)
				(type default)
			)
			(layer "F.Fab")
		)
		(fp_line
			(start 0.12065 -0.2794)
			(end 0.12065 -0.3048)
			(stroke
				(width 0.1)
				(type default)
			)
			(layer "F.Fab")
		)
		(fp_line
			(start 0.12065 -0.3048)
			(end 0.67945 -0.3048)
			(stroke
				(width 0.1)
				(type default)
			)
			(layer "F.Fab")
		)
		(fp_line
			(start 0.67945 -0.3048)
			(end 0.67945 0.3048)
			(stroke
				(width 0.1)
				(type default)
			)
			(layer "F.Fab")
		)
		(fp_line
			(start -0.67945 -0.305054)
			(end -0.12065 -0.305054)
			(stroke
				(width 0.1)
				(type default)
			)
			(layer "F.Fab")
		)
		(fp_line
			(start -0.12065 -0.305054)
			(end -0.12065 -0.2794)
			(stroke
				(width 0.1)
				(type default)
			)
			(layer "F.Fab")
		)
		(pad "1" smd circle
			(at -0.40005 0 270)
			(size 0 0)
			(layers "F.Cu" "F.Mask" "F.Paste")
			(net "HP_LVC3_OCP_V3_1_EN")
		)
		(pad "2" smd circle
			(at 0.40005 0 270)
			(size 0 0)
			(layers "F.Cu" "F.Mask" "F.Paste")
			(net "P3V3_OCP_EN_1_R2")
		)
	)
)
